# T6G (Grand Teton) — schematic netlist excerpt (pin names and nets, part order shuffled) for the footprints in the layout excerpt that follows; sources: Cadence DE-HDL packaged netlist, KiCad conversion of 04192023_DAF0TMB3IC0_F0TG_MB_C_brd_V02_OCP.brd

R1309  Q_RES  4.7K 1% EMPTY  pkg 0402LF  page 357 : A = GND ; B = INA230_6_A0
C947  Q_CAP_DIFFBUS  DIFF BUS_0.22UF 6.3V 20% X6S  pkg C0201  page 63 : \1\ = P5E_CPU0_P1_TX_C_DP<9> ; \2\ = P5E_CPU0_P1_TX_DP<9>
PR3856  Q_RES  1.33K 1% CHIP  pkg 0402LF  page 141 : A = GND ; B = P3V3_OCP_ILIMIT_2

(kicad_pcb
	(version 20260206)
	(generator "pcbnew")
	(generator_version "10.0")
	(general
		(thickness 1.6)
		(legacy_teardrops no)
	)
	(paper "A4")
	(title_block
		(title "04192023_DAF0TMB3IC0_F0TG_MB_C_brd_V02_OCP.brd")
		(comment 1 "Grand Teton / footprints 3037-3039 of 8354")
	)
	(layers
		(0 "F.Cu" signal "TOP")
		(4 "In1.Cu" signal "GND")
		(6 "In2.Cu" signal "IN1")
		(8 "In3.Cu" signal "GND1")
		(10 "In4.Cu" signal "IN2")
		(12 "In5.Cu" signal "GND2")
		(14 "In6.Cu" signal "IN3")
		(16 "In7.Cu" signal "GND3")
		(18 "In8.Cu" signal "VCC")
		(20 "In9.Cu" signal "VCC1")
		(22 "In10.Cu" signal "GND4")
		(24 "In11.Cu" signal "IN4")
		(26 "In12.Cu" signal "GND5")
		(28 "In13.Cu" signal "IN5")
		(30 "In14.Cu" signal "GND6")
		(32 "In15.Cu" signal "IN6")
		(34 "In16.Cu" signal "GND7")
		(2 "B.Cu" signal "BOTTOM")
		(9 "F.Adhes" user "F.Adhesive")
		(11 "B.Adhes" user "B.Adhesive")
		(13 "F.Paste" user "Package Geometry/Pastemask Top")
		(15 "B.Paste" user "Package Geometry/Pastemask Bottom")
		(5 "F.SilkS" user "Ref Des/Silkscreen Top")
		(7 "B.SilkS" user "Ref Des/Silkscreen Bottom")
		(1 "F.Mask" user "Board Geometry/Soldermask Top")
		(3 "B.Mask" user "Board Geometry/Soldermask Bottom")
		(17 "Dwgs.User" user "User.Drawings")
		(19 "Cmts.User" user "User.Comments")
		(21 "Eco1.User" user "User.Eco1")
		(23 "Eco2.User" user "User.Eco2")
		(25 "Edge.Cuts" user "Board Geometry/Outline")
		(27 "Margin" user)
		(31 "F.CrtYd" user "Package Geometry/Place Bound Top")
		(29 "B.CrtYd" user "Package Geometry/Place Bound Bottom")
		(35 "F.Fab" user "Ref Des/Assembly Top")
		(33 "B.Fab" user "Ref Des/Assembly Bottom")
	)
	(footprint ""
		(layer "F.Cu")
		(at 391.291318 -76.407264)
		(property "Reference" "R1309"
			(at 0 0 0)
			(layer "F.SilkS")
			(hide yes)
			(effects
				(font
					(size 1.27 1.27)
				)
			)
		)
		(property "Value" ""
			(at 0 0 0)
			(layer "F.Fab")
			(effects
				(font
					(size 1.27 1.27)
				)
			)
		)
		(duplicate_pad_numbers_are_jumpers no)
		(fp_line
			(start -0.7874 -0.4064)
			(end 0.7874 -0.4064)
			(stroke
				(width 0.1524)
				(type default)
			)
			(layer "F.SilkS")
		)
		(fp_line
			(start -0.7874 0.4064)
			(end -0.7874 -0.4064)
			(stroke
				(width 0.1524)
				(type default)
			)
			(layer "F.SilkS")
		)
		(fp_line
			(start 0.7874 -0.4064)
			(end 0.7874 0.4064)
			(stroke
				(width 0.1524)
				(type default)
			)
			(layer "F.SilkS")
		)
		(fp_line
			(start 0.7874 0.4064)
			(end -0.7874 0.4064)
			(stroke
				(width 0.1524)
				(type default)
			)
			(layer "F.SilkS")
		)
		(fp_line
			(start -0.67945 -0.305054)
			(end -0.12065 -0.305054)
			(stroke
				(width 0.1)
				(type default)
			)
			(layer "F.Fab")
		)
		(fp_line
			(start -0.67945 0.3048)
			(end -0.67945 -0.305054)
			(stroke
				(width 0.1)
				(type default)
			)
			(layer "F.Fab")
		)
		(fp_line
			(start -0.12065 -0.305054)
			(end -0.12065 -0.2794)
			(stroke
				(width 0.1)
				(type default)
			)
			(layer "F.Fab")
		)
		(fp_line
			(start -0.12065 -0.2794)
			(end 0.12065 -0.2794)
			(stroke
				(width 0.1)
				(type default)
			)
			(layer "F.Fab")
		)
		(fp_line
			(start -0.12065 0.2794)
			(end -0.12065 0.3048)
			(stroke
				(width 0.1)
				(type default)
			)
			(layer "F.Fab")
		)
		(fp_line
			(start -0.12065 0.3048)
			(end -0.67945 0.3048)
			(stroke
				(width 0.1)
				(type default)
			)
			(layer "F.Fab")
		)
		(fp_line
			(start 0.120396 0.2794)
			(end -0.12065 0.2794)
			(stroke
				(width 0.1)
				(type default)
			)
			(layer "F.Fab")
		)
		(fp_line
			(start 0.120396 0.3048)
			(end 0.120396 0.2794)
			(stroke
				(width 0.1)
				(type default)
			)
			(layer "F.Fab")
		)
		(fp_line
			(start 0.12065 -0.3048)
			(end 0.67945 -0.3048)
			(stroke
				(width 0.1)
				(type default)
			)
			(layer "F.Fab")
		)
		(fp_line
			(start 0.12065 -0.2794)
			(end 0.12065 -0.3048)
			(stroke
				(width 0.1)
				(type default)
			)
			(layer "F.Fab")
		)
		(fp_line
			(start 0.67945 -0.3048)
			(end 0.67945 0.3048)
			(stroke
				(width 0.1)
				(type default)
			)
			(layer "F.Fab")
		)
		(fp_line
			(start 0.67945 0.3048)
			(end 0.120396 0.3048)
			(stroke
				(width 0.1)
				(type default)
			)
			(layer "F.Fab")
		)
		(pad "1" smd circle
			(at -0.40005 0)
			(size 0 0)
			(layers "F.Cu" "F.Mask" "F.Paste")
			(net "GND")
		)
		(pad "2" smd circle
			(at 0.40005 0)
			(size 0 0)
			(layers "F.Cu" "F.Mask" "F.Paste")
			(net "INA230_6_A0")
		)
	)
	(footprint ""
		(layer "F.Cu")
		(at 90.380312 -74.52106 -90)
		(property "Reference" "PR3856"
			(at 0 0 270)
			(layer "F.SilkS")
			(hide yes)
			(effects
				(font
					(size 1.27 1.27)
				)
			)
		)
		(property "Value" ""
			(at 0 0 270)
			(layer "F.Fab")
			(effects
				(font
					(size 1.27 1.27)
				)
			)
		)
		(duplicate_pad_numbers_are_jumpers no)
		(fp_line
			(start -0.7874 0.4064)
			(end -0.7874 -0.4064)
			(stroke
				(width 0.1524)
				(type default)
			)
			(layer "F.SilkS")
		)
		(fp_line
			(start 0.7874 0.4064)
			(end -0.7874 0.4064)
			(stroke
				(width 0.1524)
				(type default)
			)
			(layer "F.SilkS")
		)
		(fp_line
			(start -0.7874 -0.4064)
			(end 0.7874 -0.4064)
			(stroke
				(width 0.1524)
				(type default)
			)
			(layer "F.SilkS")
		)
		(fp_line
			(start 0.7874 -0.4064)
			(end 0.7874 0.4064)
			(stroke
				(width 0.1524)
				(type default)
			)
			(layer "F.SilkS")
		)
		(fp_line
			(start -0.67945 0.3048)
			(end -0.67945 -0.305054)
			(stroke
				(width 0.1)
				(type default)
			)
			(layer "F.Fab")
		)
		(fp_line
			(start -0.12065 0.3048)
			(end -0.67945 0.3048)
			(stroke
				(width 0.1)
				(type default)
			)
			(layer "F.Fab")
		)
		(fp_line
			(start 0.120396 0.3048)
			(end 0.120396 0.2794)
			(stroke
				(width 0.1)
				(type default)
			)
			(layer "F.Fab")
		)
		(fp_line
			(start 0.67945 0.3048)
			(end 0.120396 0.3048)
			(stroke
				(width 0.1)
				(type default)
			)
			(layer "F.Fab")
		)
		(fp_line
			(start -0.12065 0.2794)
			(end -0.12065 0.3048)
			(stroke
				(width 0.1)
				(type default)
			)
			(layer "F.Fab")
		)
		(fp_line
			(start 0.120396 0.2794)
			(end -0.12065 0.2794)
			(stroke
				(width 0.1)
				(type default)
			)
			(layer "F.Fab")
		)
		(fp_line
			(start -0.12065 -0.2794)
			(end 0.12065 -0.2794)
			(stroke
				(width 0.1)
				(type default)
			)
			(layer "F.Fab")
		)
		(fp_line
			(start 0.12065 -0.2794)
			(end 0.12065 -0.3048)
			(stroke
				(width 0.1)
				(type default)
			)
			(layer "F.Fab")
		)
		(fp_line
			(start 0.12065 -0.3048)
			(end 0.67945 -0.3048)
			(stroke
				(width 0.1)
				(type default)
			)
			(layer "F.Fab")
		)
		(fp_line
			(start 0.67945 -0.3048)
			(end 0.67945 0.3048)
			(stroke
				(width 0.1)
				(type default)
			)
			(layer "F.Fab")
		)
		(fp_line
			(start -0.67945 -0.305054)
			(end -0.12065 -0.305054)
			(stroke
				(width 0.1)
				(type default)
			)
			(layer "F.Fab")
		)
		(fp_line
			(start -0.12065 -0.305054)
			(end -0.12065 -0.2794)
			(stroke
				(width 0.1)
				(type default)
			)
			(layer "F.Fab")
		)
		(pad "1" smd circle
			(at -0.40005 0 270)
			(size 0 0)
			(layers "F.Cu" "F.Mask" "F.Paste")
			(net "GND")
		)
		(pad "2" smd circle
			(at 0.40005 0 270)
			(size 0 0)
			(layers "F.Cu" "F.Mask" "F.Paste")
			(net "P3V3_OCP_ILIMIT_2")
		)
	)
	(footprint ""
		(layer "F.Cu")
		(at 346.833444 -378.95403 -90)
		(property "Reference" "C947"
			(at 0 0 270)
			(layer "F.SilkS")
			(hide yes)
			(effects
				(font
					(size 1.27 1.27)
				)
			)
		)
		(property "Value" ""
			(at 0 0 270)
			(layer "F.Fab")
			(effects
				(font
					(size 1.27 1.27)
				)
			)
		)
		(duplicate_pad_numbers_are_jumpers no)
		(fp_line
			(start -0.299974 0.150114)
			(end -0.299974 -0.150114)
			(stroke
				(width 0.1)
				(type default)
			)
			(layer "F.Fab")
		)
		(fp_line
			(start 0.299974 0.150114)
			(end -0.299974 0.150114)
			(stroke
				(width 0.1)
				(type default)
			)
			(layer "F.Fab")
		)
		(fp_line
			(start -0.299974 -0.150114)
			(end 0.299974 -0.150114)
			(stroke
				(width 0.1)
				(type default)
			)
			(layer "F.Fab")
		)
		(fp_line
			(start 0.299974 -0.150114)
			(end 0.299974 0.150114)
			(stroke
				(width 0.1)
				(type default)
			)
			(layer "F.Fab")
		)
		(pad "1" smd rect
			(at -0.2667 0 270)
			(size 0.3048 0.381)
			(layers "F.Cu" "F.Mask" "F.Paste")
			(net "P5E_CPU0_P1_TX_C_DP<9>")
		)
		(pad "2" smd rect
			(at 0.2667 0 270)
			(size 0.3048 0.381)
			(layers "F.Cu" "F.Mask" "F.Paste")
			(net "P5E_CPU0_P1_TX_DP<9>")
		)
	)
)
